(kicad_pcb
	(version 20260206)
	(generator "pcbnew")
	(generator_version "10.0")
	(general
		(thickness 1.6)
		(legacy_teardrops no)
	)
	(paper "A4")
	(title_block
		(title "panther-plus-userver — 13130-1b_20150205.brd")
		(comment 1 "Honey Badger (Wiwynn) / footprints 1497-1504 of 1509")
	)
	(layers
		(0 "F.Cu" signal "TOP")
		(4 "In1.Cu" signal "L2")
		(6 "In2.Cu" signal "L3")
		(8 "In3.Cu" signal "L4")
		(10 "In4.Cu" signal "L5")
		(12 "In5.Cu" signal "L6")
		(14 "In6.Cu" signal "L7")
		(16 "In7.Cu" signal "L8")
		(18 "In8.Cu" signal "L9")
		(20 "In9.Cu" signal "L10")
		(22 "In10.Cu" signal "L11")
		(2 "B.Cu" signal "BOTTOM")
		(9 "F.Adhes" user "F.Adhesive")
		(11 "B.Adhes" user "B.Adhesive")
		(13 "F.Paste" user "Package Geometry/Pastemask Top")
		(15 "B.Paste" user "Package Geometry/Pastemask Bottom")
		(5 "F.SilkS" user "Ref Des/Silkscreen Top")
		(7 "B.SilkS" user "Ref Des/Silkscreen Bottom")
		(1 "F.Mask" user "Board Geometry/Soldermask Top")
		(3 "B.Mask" user "Board Geometry/Soldermask Bottom")
		(17 "Dwgs.User" user "User.Drawings")
		(19 "Cmts.User" user "User.Comments")
		(21 "Eco1.User" user "User.Eco1")
		(23 "Eco2.User" user "User.Eco2")
		(25 "Edge.Cuts" user "Board Geometry/Outline")
		(27 "Margin" user)
		(31 "F.CrtYd" user "Package Geometry/Place Bound Top")
		(29 "B.CrtYd" user "Package Geometry/Place Bound Bottom")
		(35 "F.Fab" user "Ref Des/Assembly Top")
		(33 "B.Fab" user "Ref Des/Assembly Bottom")
	)
	(footprint ""
		(layer "B.Cu")
		(at 46.1264 -28.321)
		(property "Reference" "R438"
			(at 0 0 0)
			(layer "B.SilkS")
			(hide yes)
			(effects
				(font
					(size 1.27 1.27)
				)
				(justify mirror)
			)
		)
		(property "Value" "4K7R2F-GP"
			(at -1.7907 -1.1176 0)
			(unlocked yes)
			(layer "B.Fab")
			(hide yes)
			(effects
				(font
					(size 1.016 1.016)
					(thickness 0.1524)
				)
				(justify mirror)
			)
		)
		(property "Device Type" "R402H16"
			(at -1.7907 -2.6416 0)
			(unlocked yes)
			(layer "B.Fab")
			(hide yes)
			(effects
				(font
					(size 1.016 1.016)
					(thickness 0.1524)
				)
				(justify mirror)
			)
		)
		(duplicate_pad_numbers_are_jumpers no)
		(fp_rect
			(start 0.381 0.8382)
			(end -0.381 -0.8382)
			(stroke
				(width 0)
				(type default)
			)
			(fill no)
			(layer "B.CrtYd")
		)
		(fp_rect
			(start 0.381 0.8382)
			(end -0.381 -0.8382)
			(stroke
				(width 0)
				(type default)
			)
			(fill no)
			(layer "B.Fab")
		)
		(pad "1" smd custom
			(at 0 -0.4318 180)
			(size 0.127 0.127)
			(layers "B.Cu" "B.Mask" "B.Paste")
			(net "P3V3")
			(options
				(clearance outline)
				(anchor circle)
			)
			(primitives
				(gr_poly
					(pts
						(arc
							(start -0.2032 0.2794)
							(mid -0.239121 0.264521)
							(end -0.254 0.2286)
						)
						(arc
							(start -0.254 -0.2286)
							(mid -0.239121 -0.264521)
							(end -0.2032 -0.2794)
						)
						(arc
							(start 0.2032 -0.2794)
							(mid 0.239121 -0.264521)
							(end 0.254 -0.2286)
						)
						(arc
							(start 0.254 0.2286)
							(mid 0.239121 0.264521)
							(end 0.2032 0.2794)
						)
					)
					(width 0)
					(fill yes)
				)
			)
		)
		(pad "2" smd custom
			(at 0 0.4318 180)
			(size 0.127 0.127)
			(layers "B.Cu" "B.Mask" "B.Paste")
			(net "CLKBUFF_OE6#")
			(options
				(clearance outline)
				(anchor circle)
			)
			(primitives
				(gr_poly
					(pts
						(arc
							(start -0.2032 0.2794)
							(mid -0.239121 0.264521)
							(end -0.254 0.2286)
						)
						(arc
							(start -0.254 -0.2286)
							(mid -0.239121 -0.264521)
							(end -0.2032 -0.2794)
						)
						(arc
							(start 0.2032 -0.2794)
							(mid 0.239121 -0.264521)
							(end 0.254 -0.2286)
						)
						(arc
							(start 0.254 0.2286)
							(mid 0.239121 0.264521)
							(end 0.2032 0.2794)
						)
					)
					(width 0)
					(fill yes)
				)
			)
		)
	)
	(footprint ""
		(layer "B.Cu")
		(at 130.81 -25.273 180)
		(property "Reference" "Q2"
			(at 0 0 0)
			(layer "B.SilkS")
			(hide yes)
			(effects
				(font
					(size 1.27 1.27)
				)
				(justify mirror)
			)
		)
		(property "Value" "MMBT3904TT1G-GP"
			(at 0 -9.7282 180)
			(unlocked yes)
			(layer "B.Fab")
			(hide yes)
			(effects
				(font
					(size 1.016 1.016)
					(thickness 0.1524)
				)
				(justify mirror)
			)
		)
		(property "Device Type" "SC75CBE1D6H36"
			(at 0 -11.6332 180)
			(unlocked yes)
			(layer "B.Fab")
			(hide yes)
			(effects
				(font
					(size 1.016 1.016)
					(thickness 0.1524)
				)
				(justify mirror)
			)
		)
		(duplicate_pad_numbers_are_jumpers no)
		(fp_poly
			(pts
				(xy -0.381 -1.1938) (xy 0.381 -1.1938) (xy 0.381 -0.6604) (xy 1.0541 -0.6604) (xy 1.0541 0.6604)
				(xy 0.889 0.6604) (xy 0.889 1.1938) (xy -0.889 1.1938) (xy -0.889 0.6604) (xy -1.0541 0.6604) (xy -1.0541 -0.6604)
				(xy -0.381 -0.6604)
			)
			(stroke
				(width 0)
				(type default)
			)
			(fill no)
			(layer "B.CrtYd")
		)
		(fp_poly
			(pts
				(xy -0.381 -1.1938) (xy 0.381 -1.1938) (xy 0.381 -0.6604) (xy 1.0541 -0.6604) (xy 1.0541 0.6604)
				(xy 0.889 0.6604) (xy 0.889 1.1938) (xy -0.889 1.1938) (xy -0.889 0.6604) (xy -1.0541 0.6604) (xy -1.0541 -0.6604)
				(xy -0.381 -0.6604)
			)
			(stroke
				(width 0)
				(type default)
			)
			(fill no)
			(layer "B.Fab")
		)
		(pad "B" smd custom
			(at 0.508 0.6604)
			(size 0.127 0.127)
			(layers "B.Cu" "B.Mask" "B.Paste")
			(net "H_THERMTRIP_N_R")
			(options
				(clearance outline)
				(anchor circle)
			)
			(primitives
				(gr_poly
					(pts
						(arc
							(start -0.0508 -0.4064)
							(mid -0.194484 -0.346884)
							(end -0.254 -0.2032)
						)
						(arc
							(start -0.254 0.2032)
							(mid -0.194484 0.346884)
							(end -0.0508 0.4064)
						)
						(arc
							(start 0.0508 0.4064)
							(mid 0.194484 0.346884)
							(end 0.254 0.2032)
						)
						(arc
							(start 0.254 -0.2032)
							(mid 0.194484 -0.346884)
							(end 0.0508 -0.4064)
						)
					)
					(width 0)
					(fill yes)
				)
			)
		)
		(pad "C" smd custom
			(at 0 -0.6604)
			(size 0.127 0.127)
			(layers "B.Cu" "B.Mask" "B.Paste")
			(net "CPU_THERMTRIP_LVC#")
			(options
				(clearance outline)
				(anchor circle)
			)
			(primitives
				(gr_poly
					(pts
						(arc
							(start -0.0508 -0.4064)
							(mid -0.194484 -0.346884)
							(end -0.254 -0.2032)
						)
						(arc
							(start -0.254 0.2032)
							(mid -0.194484 0.346884)
							(end -0.0508 0.4064)
						)
						(arc
							(start 0.0508 0.4064)
							(mid 0.194484 0.346884)
							(end 0.254 0.2032)
						)
						(arc
							(start 0.254 -0.2032)
							(mid 0.194484 -0.346884)
							(end 0.0508 -0.4064)
						)
					)
					(width 0)
					(fill yes)
				)
			)
		)
		(pad "E" smd custom
			(at -0.508 0.6604)
			(size 0.127 0.127)
			(layers "B.Cu" "B.Mask" "B.Paste")
			(net "CPU_THERMTRIP#")
			(options
				(clearance outline)
				(anchor circle)
			)
			(primitives
				(gr_poly
					(pts
						(arc
							(start -0.0508 -0.4064)
							(mid -0.194484 -0.346884)
							(end -0.254 -0.2032)
						)
						(arc
							(start -0.254 0.2032)
							(mid -0.194484 0.346884)
							(end -0.0508 0.4064)
						)
						(arc
							(start 0.0508 0.4064)
							(mid 0.194484 0.346884)
							(end 0.254 0.2032)
						)
						(arc
							(start 0.254 -0.2032)
							(mid 0.194484 -0.346884)
							(end 0.0508 -0.4064)
						)
					)
					(width 0)
					(fill yes)
				)
			)
		)
	)
	(footprint ""
		(layer "B.Cu")
		(at 20.193 -12.7)
		(property "Reference" "C287"
			(at 0 0 0)
			(layer "B.SilkS")
			(hide yes)
			(effects
				(font
					(size 1.27 1.27)
				)
				(justify mirror)
			)
		)
		(property "Value" "SCD1U16V2KX-3GP"
			(at -1.1811 -2.7051 0)
			(unlocked yes)
			(layer "B.Fab")
			(hide yes)
			(effects
				(font
					(size 1.016 1.016)
					(thickness 0.1524)
				)
				(justify mirror)
			)
		)
		(property "Device Type" "C402H22"
			(at -1.1811 -4.2291 0)
			(unlocked yes)
			(layer "B.Fab")
			(hide yes)
			(effects
				(font
					(size 1.016 1.016)
					(thickness 0.1524)
				)
				(justify mirror)
			)
		)
		(duplicate_pad_numbers_are_jumpers no)
		(fp_rect
			(start 0.381 0.7366)
			(end -0.381 -0.7366)
			(stroke
				(width 0)
				(type default)
			)
			(fill no)
			(layer "B.CrtYd")
		)
		(fp_rect
			(start 0.381 0.7366)
			(end -0.381 -0.7366)
			(stroke
				(width 0)
				(type default)
			)
			(fill no)
			(layer "B.Fab")
		)
		(pad "1" smd custom
			(at 0 -0.4572 180)
			(size 0.1143 0.1143)
			(layers "B.Cu" "B.Mask" "B.Paste")
			(net "P2E_CPU_ETH10G_C_TX_DN11")
			(options
				(clearance outline)
				(anchor circle)
			)
			(primitives
				(gr_poly
					(pts
						(arc
							(start -0.254 0.1778)
							(mid -0.239121 0.213721)
							(end -0.2032 0.2286)
						)
						(arc
							(start 0.2032 0.2286)
							(mid 0.239121 0.213721)
							(end 0.254 0.1778)
						)
						(arc
							(start 0.254 -0.1778)
							(mid 0.239121 -0.213721)
							(end 0.2032 -0.2286)
						)
						(arc
							(start -0.2032 -0.2286)
							(mid -0.239121 -0.213721)
							(end -0.254 -0.1778)
						)
					)
					(width 0)
					(fill yes)
				)
			)
		)
		(pad "2" smd custom
			(at 0 0.4572 180)
			(size 0.1143 0.1143)
			(layers "B.Cu" "B.Mask" "B.Paste")
			(net "P2E_CPU_ETH10G_TX_DN11")
			(options
				(clearance outline)
				(anchor circle)
			)
			(primitives
				(gr_poly
					(pts
						(arc
							(start -0.254 0.1778)
							(mid -0.239121 0.213721)
							(end -0.2032 0.2286)
						)
						(arc
							(start 0.2032 0.2286)
							(mid 0.239121 0.213721)
							(end 0.254 0.1778)
						)
						(arc
							(start 0.254 -0.1778)
							(mid 0.239121 -0.213721)
							(end 0.2032 -0.2286)
						)
						(arc
							(start -0.2032 -0.2286)
							(mid -0.239121 -0.213721)
							(end -0.254 -0.1778)
						)
					)
					(width 0)
					(fill yes)
				)
			)
		)
	)
	(footprint ""
		(layer "B.Cu")
		(at 144.399 -44.704 -90)
		(property "Reference" "R493"
			(at 0 0 90)
			(layer "B.SilkS")
			(hide yes)
			(effects
				(font
					(size 1.27 1.27)
				)
				(justify mirror)
			)
		)
		(property "Value" "1KR2F-3-GP"
			(at -1.7907 -1.1176 270)
			(unlocked yes)
			(layer "B.Fab")
			(hide yes)
			(effects
				(font
					(size 1.016 1.016)
					(thickness 0.1524)
				)
				(justify mirror)
			)
		)
		(property "Device Type" "R402H16"
			(at -1.7907 -2.6416 270)
			(unlocked yes)
			(layer "B.Fab")
			(hide yes)
			(effects
				(font
					(size 1.016 1.016)
					(thickness 0.1524)
				)
				(justify mirror)
			)
		)
		(duplicate_pad_numbers_are_jumpers no)
		(fp_rect
			(start 0.381 0.8382)
			(end -0.381 -0.8382)
			(stroke
				(width 0)
				(type default)
			)
			(fill no)
			(layer "B.CrtYd")
		)
		(fp_rect
			(start 0.381 0.8382)
			(end -0.381 -0.8382)
			(stroke
				(width 0)
				(type default)
			)
			(fill no)
			(layer "B.Fab")
		)
		(pad "1" smd custom
			(at 0 -0.4318 90)
			(size 0.127 0.127)
			(layers "B.Cu" "B.Mask" "B.Paste")
			(net "JTAG_PLD_TDI")
			(options
				(clearance outline)
				(anchor circle)
			)
			(primitives
				(gr_poly
					(pts
						(arc
							(start -0.2032 0.2794)
							(mid -0.239121 0.264521)
							(end -0.254 0.2286)
						)
						(arc
							(start -0.254 -0.2286)
							(mid -0.239121 -0.264521)
							(end -0.2032 -0.2794)
						)
						(arc
							(start 0.2032 -0.2794)
							(mid 0.239121 -0.264521)
							(end 0.254 -0.2286)
						)
						(arc
							(start 0.254 0.2286)
							(mid 0.239121 0.264521)
							(end 0.2032 0.2794)
						)
					)
					(width 0)
					(fill yes)
				)
			)
		)
		(pad "2" smd custom
			(at 0 0.4318 90)
			(size 0.127 0.127)
			(layers "B.Cu" "B.Mask" "B.Paste")
			(net "GND")
			(options
				(clearance outline)
				(anchor circle)
			)
			(primitives
				(gr_poly
					(pts
						(arc
							(start -0.2032 0.2794)
							(mid -0.239121 0.264521)
							(end -0.254 0.2286)
						)
						(arc
							(start -0.254 -0.2286)
							(mid -0.239121 -0.264521)
							(end -0.2032 -0.2794)
						)
						(arc
							(start 0.2032 -0.2794)
							(mid 0.239121 -0.264521)
							(end 0.254 -0.2286)
						)
						(arc
							(start 0.254 0.2286)
							(mid 0.239121 0.264521)
							(end 0.2032 0.2794)
						)
					)
					(width 0)
					(fill yes)
				)
			)
		)
	)
	(footprint ""
		(layer "B.Cu")
		(at 204.3176 -42.3418 90)
		(property "Reference" "C349"
			(at 0 0 90)
			(layer "B.SilkS")
			(hide yes)
			(effects
				(font
					(size 1.27 1.27)
				)
				(justify mirror)
			)
		)
		(property "Value" "SCD1U16V2KX-3GP"
			(at -1.8923 -1.2065 90)
			(unlocked yes)
			(layer "B.Fab")
			(hide yes)
			(effects
				(font
					(size 1.016 1.016)
					(thickness 0.1524)
				)
				(justify mirror)
			)
		)
		(property "Device Type" "C402H22"
			(at -1.8923 -2.7305 90)
			(unlocked yes)
			(layer "B.Fab")
			(hide yes)
			(effects
				(font
					(size 1.016 1.016)
					(thickness 0.1524)
				)
				(justify mirror)
			)
		)
		(duplicate_pad_numbers_are_jumpers no)
		(fp_rect
			(start 0.381 0.7366)
			(end -0.381 -0.7366)
			(stroke
				(width 0)
				(type default)
			)
			(fill no)
			(layer "B.CrtYd")
		)
		(fp_rect
			(start 0.381 0.7366)
			(end -0.381 -0.7366)
			(stroke
				(width 0)
				(type default)
			)
			(fill no)
			(layer "B.Fab")
		)
		(pad "1" smd custom
			(at 0 -0.4572 270)
			(size 0.1143 0.1143)
			(layers "B.Cu" "B.Mask" "B.Paste")
			(net "PV_VDDR")
			(options
				(clearance outline)
				(anchor circle)
			)
			(primitives
				(gr_poly
					(pts
						(arc
							(start -0.254 0.1778)
							(mid -0.239121 0.213721)
							(end -0.2032 0.2286)
						)
						(arc
							(start 0.2032 0.2286)
							(mid 0.239121 0.213721)
							(end 0.254 0.1778)
						)
						(arc
							(start 0.254 -0.1778)
							(mid 0.239121 -0.213721)
							(end 0.2032 -0.2286)
						)
						(arc
							(start -0.2032 -0.2286)
							(mid -0.239121 -0.213721)
							(end -0.254 -0.1778)
						)
					)
					(width 0)
					(fill yes)
				)
			)
		)
		(pad "2" smd custom
			(at 0 0.4572 270)
			(size 0.1143 0.1143)
			(layers "B.Cu" "B.Mask" "B.Paste")
			(net "GND")
			(options
				(clearance outline)
				(anchor circle)
			)
			(primitives
				(gr_poly
					(pts
						(arc
							(start -0.254 0.1778)
							(mid -0.239121 0.213721)
							(end -0.2032 0.2286)
						)
						(arc
							(start 0.2032 0.2286)
							(mid 0.239121 0.213721)
							(end 0.254 0.1778)
						)
						(arc
							(start 0.254 -0.1778)
							(mid 0.239121 -0.213721)
							(end 0.2032 -0.2286)
						)
						(arc
							(start -0.2032 -0.2286)
							(mid -0.239121 -0.213721)
							(end -0.254 -0.1778)
						)
					)
					(width 0)
					(fill yes)
				)
			)
		)
	)
	(footprint ""
		(layer "B.Cu")
		(at 15.875 -64.643 90)
		(property "Reference" "C30"
			(at 0 0 90)
			(layer "B.SilkS")
			(hide yes)
			(effects
				(font
					(size 1.27 1.27)
				)
				(justify mirror)
			)
		)
		(property "Value" "SC1U6D3V2KX-GP"
			(at -1.8923 -1.2065 90)
			(unlocked yes)
			(layer "B.Fab")
			(hide yes)
			(effects
				(font
					(size 1.016 1.016)
					(thickness 0.1524)
				)
				(justify mirror)
			)
		)
		(property "Device Type" "C402H22"
			(at -1.8923 -2.7305 90)
			(unlocked yes)
			(layer "B.Fab")
			(hide yes)
			(effects
				(font
					(size 1.016 1.016)
					(thickness 0.1524)
				)
				(justify mirror)
			)
		)
		(duplicate_pad_numbers_are_jumpers no)
		(fp_rect
			(start 0.381 0.7366)
			(end -0.381 -0.7366)
			(stroke
				(width 0)
				(type default)
			)
			(fill no)
			(layer "B.CrtYd")
		)
		(fp_rect
			(start 0.381 0.7366)
			(end -0.381 -0.7366)
			(stroke
				(width 0)
				(type default)
			)
			(fill no)
			(layer "B.Fab")
		)
		(pad "1" smd custom
			(at 0 -0.4572 270)
			(size 0.1143 0.1143)
			(layers "B.Cu" "B.Mask" "B.Paste")
			(net "P3V3")
			(options
				(clearance outline)
				(anchor circle)
			)
			(primitives
				(gr_poly
					(pts
						(arc
							(start -0.254 0.1778)
							(mid -0.239121 0.213721)
							(end -0.2032 0.2286)
						)
						(arc
							(start 0.2032 0.2286)
							(mid 0.239121 0.213721)
							(end 0.254 0.1778)
						)
						(arc
							(start 0.254 -0.1778)
							(mid 0.239121 -0.213721)
							(end 0.2032 -0.2286)
						)
						(arc
							(start -0.2032 -0.2286)
							(mid -0.239121 -0.213721)
							(end -0.254 -0.1778)
						)
					)
					(width 0)
					(fill yes)
				)
			)
		)
		(pad "2" smd custom
			(at 0 0.4572 270)
			(size 0.1143 0.1143)
			(layers "B.Cu" "B.Mask" "B.Paste")
			(net "GND")
			(options
				(clearance outline)
				(anchor circle)
			)
			(primitives
				(gr_poly
					(pts
						(arc
							(start -0.254 0.1778)
							(mid -0.239121 0.213721)
							(end -0.2032 0.2286)
						)
						(arc
							(start 0.2032 0.2286)
							(mid 0.239121 0.213721)
							(end 0.254 0.1778)
						)
						(arc
							(start 0.254 -0.1778)
							(mid 0.239121 -0.213721)
							(end 0.2032 -0.2286)
						)
						(arc
							(start -0.2032 -0.2286)
							(mid -0.239121 -0.213721)
							(end -0.254 -0.1778)
						)
					)
					(width 0)
					(fill yes)
				)
			)
		)
	)
	(footprint ""
		(layer "B.Cu")
		(at 29.464 -12.7)
		(property "Reference" "C271"
			(at 0 0 0)
			(layer "B.SilkS")
			(hide yes)
			(effects
				(font
					(size 1.27 1.27)
				)
				(justify mirror)
			)
		)
		(property "Value" "SCD1U16V2KX-3GP"
			(at -1.1811 -2.7051 0)
			(unlocked yes)
			(layer "B.Fab")
			(hide yes)
			(effects
				(font
					(size 1.016 1.016)
					(thickness 0.1524)
				)
				(justify mirror)
			)
		)
		(property "Device Type" "C402H22"
			(at -1.1811 -4.2291 0)
			(unlocked yes)
			(layer "B.Fab")
			(hide yes)
			(effects
				(font
					(size 1.016 1.016)
					(thickness 0.1524)
				)
				(justify mirror)
			)
		)
		(duplicate_pad_numbers_are_jumpers no)
		(fp_rect
			(start 0.381 0.7366)
			(end -0.381 -0.7366)
			(stroke
				(width 0)
				(type default)
			)
			(fill no)
			(layer "B.CrtYd")
		)
		(fp_rect
			(start 0.381 0.7366)
			(end -0.381 -0.7366)
			(stroke
				(width 0)
				(type default)
			)
			(fill no)
			(layer "B.Fab")
		)
		(pad "1" smd custom
			(at 0 -0.4572 180)
			(size 0.1143 0.1143)
			(layers "B.Cu" "B.Mask" "B.Paste")
			(net "P2E_CPU_ETH10G_C_TX_DN8")
			(options
				(clearance outline)
				(anchor circle)
			)
			(primitives
				(gr_poly
					(pts
						(arc
							(start -0.254 0.1778)
							(mid -0.239121 0.213721)
							(end -0.2032 0.2286)
						)
						(arc
							(start 0.2032 0.2286)
							(mid 0.239121 0.213721)
							(end 0.254 0.1778)
						)
						(arc
							(start 0.254 -0.1778)
							(mid 0.239121 -0.213721)
							(end 0.2032 -0.2286)
						)
						(arc
							(start -0.2032 -0.2286)
							(mid -0.239121 -0.213721)
							(end -0.254 -0.1778)
						)
					)
					(width 0)
					(fill yes)
				)
			)
		)
		(pad "2" smd custom
			(at 0 0.4572 180)
			(size 0.1143 0.1143)
			(layers "B.Cu" "B.Mask" "B.Paste")
			(net "P2E_CPU_ETH10G_TX_DN8")
			(options
				(clearance outline)
				(anchor circle)
			)
			(primitives
				(gr_poly
					(pts
						(arc
							(start -0.254 0.1778)
							(mid -0.239121 0.213721)
							(end -0.2032 0.2286)
						)
						(arc
							(start 0.2032 0.2286)
							(mid 0.239121 0.213721)
							(end 0.254 0.1778)
						)
						(arc
							(start 0.254 -0.1778)
							(mid 0.239121 -0.213721)
							(end 0.2032 -0.2286)
						)
						(arc
							(start -0.2032 -0.2286)
							(mid -0.239121 -0.213721)
							(end -0.254 -0.1778)
						)
					)
					(width 0)
					(fill yes)
				)
			)
		)
	)
	(footprint ""
		(layer "B.Cu")
		(at 203.4794 -60.706 90)
		(property "Reference" "PC155"
			(at 0 0 90)
			(layer "B.SilkS")
			(hide yes)
			(effects
				(font
					(size 1.27 1.27)
				)
				(justify mirror)
			)
		)
		(property "Value" "SC22U6D3V5MX-2GP"
			(at 0 -4.9022 90)
			(unlocked yes)
			(layer "B.Fab")
			(hide yes)
			(effects
				(font
					(size 1.016 1.016)
					(thickness 0.1524)
				)
				(justify mirror)
			)
		)
		(property "Device Type" "C805H58"
			(at 0 -6.8072 90)
			(unlocked yes)
			(layer "B.Fab")
			(hide yes)
			(effects
				(font
					(size 1.016 1.016)
					(thickness 0.1524)
				)
				(justify mirror)
			)
		)
		(duplicate_pad_numbers_are_jumpers no)
		(fp_line
			(start -0.6096 0)
			(end 0.6096 0)
			(stroke
				(width 0.3048)
				(type default)
			)
			(layer "B.SilkS")
		)
		(fp_poly
			(pts
				(xy 0.9017 1.4351) (xy -0.9017 1.4351) (xy -0.9017 -1.4351) (xy 0.9017 -1.4351)
			)
			(stroke
				(width 0)
				(type default)
			)
			(fill no)
			(layer "B.CrtYd")
		)
		(fp_poly
			(pts
				(xy -0.9017 1.4351) (xy -0.9017 -1.4351) (xy 0.9017 -1.4351) (xy 0.9017 1.4351)
			)
			(stroke
				(width 0)
				(type default)
			)
			(fill no)
			(layer "B.Fab")
		)
		(pad "1" smd rect
			(at 0 -0.8382 270)
			(size 1.5494 0.9398)
			(layers "B.Cu" "B.Mask" "B.Paste")
			(net "PV_VDDR")
		)
		(pad "2" smd rect
			(at 0 0.8382 270)
			(size 1.5494 0.9398)
			(layers "B.Cu" "B.Mask" "B.Paste")
			(net "GND")
		)
	)
)
